FILE_TYPE = MULTI_PHYS_TABLE;

PART 'METR3904G'

{========================================================================================}
:VALUE        | PART_TYPE | MATERIAL | PART_NUMBER      = PART_NUMBER   | JEDEC_TYPE  | DESCRIPTION                              | MANUFTR | MANUF_PN     | RD_CMPLS_LVL | CMPLS_LVL | CLASS | DIP_SMD | FP_ECN | FROM_PJ        | DATA             | EE_CHECK_LIST | STANDARD | PSL | PREFERENCE | LIFECYCLE      | CREATOR | CREATEDAY    | STATUS ;
{========================================================================================}
 'METR3904-G' | 'SMLF'    | 'IC'     | 'BA039040020'(!) = 'BA039040020' |'SOT23_BEC'| 'TRANS SMD METR3904-G(40V,200MA,0.225W)' | 'MKP'   | 'METR3904-G' | 'EP(V1)'     | 'EP(V1)'  | 'IC'  | ''      | ''     | 'TU1D-MICHAEL' | 'METR3904-G.pdf' | ''            | ''               | ''  | ''         | ''               | ''      | '20111020' | ''    
 'METR3904-G' | 'SMLF'    | 'EMPTY'  | 'BA039040020'(!) = 'BA039040020' |'SOT23_BEC'| 'TRANS SMD METR3904-G(40V,200MA,0.225W)' | 'MKP'   | 'METR3904-G' | 'EP(V1)'     | 'EP(V1)'  | 'IC'  | ''      | ''     | 'TU1D-MICHAEL' | 'METR3904-G.pdf' | ''            | ''               | ''  | ''         | ''               | ''      | '20111020' | ''    

END_PART

END.

